# BASEBOARD_FAB2 (Tioga Pass) — schematic netlist excerpt (pin names and nets, part order shuffled) for the footprints in the layout excerpt that follows; sources: Cadence DE-HDL packaged netlist, KiCad conversion of Wiwynn_Tioga_Pass_MB.brd

C5P17  CAP  47UF 4V 20% X6S  pkg 0805  page 42 : A = PVCCIN_CPU0 ; B = GND
CT42  CAP  1000PF 50V 10% X7R  pkg 0402LF  page 203 : A = A_TSENSE_PVCCIN_CPU0 ; B = GND
C25W81  CAP  10.0PF 50V 5% COG  pkg 0402LF  page 252 : A = V_IO_HSYNC_J ; B = GND

(kicad_pcb
	(version 20260206)
	(generator "pcbnew")
	(generator_version "10.0")
	(general
		(thickness 1.6)
		(legacy_teardrops no)
	)
	(paper "A4")
	(title_block
		(title "Wiwynn_Tioga_Pass_MB.brd")
		(comment 1 "Tioga Pass / footprints 4382-4384 of 4770")
	)
	(layers
		(0 "F.Cu" signal "TOP")
		(4 "In1.Cu" signal "L2GND")
		(6 "In2.Cu" signal "L3")
		(8 "In3.Cu" signal "L4GND")
		(10 "In4.Cu" signal "L5")
		(12 "In5.Cu" signal "L6GND")
		(14 "In6.Cu" signal "L7VCC")
		(16 "In7.Cu" signal "L8VCC")
		(18 "In8.Cu" signal "L9GND")
		(20 "In9.Cu" signal "L10")
		(22 "In10.Cu" signal "L11GND")
		(24 "In11.Cu" signal "L12")
		(26 "In12.Cu" signal "L13GND")
		(2 "B.Cu" signal "BOTTOM")
		(9 "F.Adhes" user "F.Adhesive")
		(11 "B.Adhes" user "B.Adhesive")
		(13 "F.Paste" user "Package Geometry/Pastemask Top")
		(15 "B.Paste" user "Package Geometry/Pastemask Bottom")
		(5 "F.SilkS" user "Ref Des/Silkscreen Top")
		(7 "B.SilkS" user "Ref Des/Silkscreen Bottom")
		(1 "F.Mask" user "Board Geometry/Soldermask Top")
		(3 "B.Mask" user "Board Geometry/Soldermask Bottom")
		(17 "Dwgs.User" user "User.Drawings")
		(19 "Cmts.User" user "User.Comments")
		(21 "Eco1.User" user "User.Eco1")
		(23 "Eco2.User" user "User.Eco2")
		(25 "Edge.Cuts" user "Board Geometry/Outline")
		(27 "Margin" user)
		(31 "F.CrtYd" user "Package Geometry/Place Bound Top")
		(29 "B.CrtYd" user "Package Geometry/Place Bound Bottom")
		(35 "F.Fab" user "Ref Des/Assembly Top")
		(33 "B.Fab" user "Ref Des/Assembly Bottom")
	)
	(footprint ""
		(layer "B.Cu")
		(at 195.1736 -80.2386 90)
		(property "Reference" "CT42"
			(at 0.8382 -0.84963 90)
			(unlocked yes)
			(layer "B.SilkS")
			(effects
				(font
					(size 0.7874 0.5842)
					(thickness 0.1524)
				)
				(justify left mirror)
			)
		)
		(property "Value" ""
			(at 0 0 90)
			(layer "B.Fab")
			(effects
				(font
					(size 1.27 1.27)
				)
				(justify mirror)
			)
		)
		(duplicate_pad_numbers_are_jumpers no)
		(fp_poly
			(pts
				(xy -0.3048 -0.1016) (xy -0.3048 0.9906) (xy 0.3048 0.9906) (xy 0.3048 -0.1016)
			)
			(stroke
				(width 0)
				(type default)
			)
			(fill no)
			(layer "B.CrtYd")
		)
		(fp_line
			(start 0.3048 -0.1016)
			(end 0.3048 0.9906)
			(stroke
				(width 0.1)
				(type default)
			)
			(layer "B.Fab")
		)
		(fp_line
			(start -0.3048 -0.1016)
			(end 0.3048 -0.1016)
			(stroke
				(width 0.1)
				(type default)
			)
			(layer "B.Fab")
		)
		(fp_line
			(start 0.3048 0.9906)
			(end -0.3048 0.9906)
			(stroke
				(width 0.1)
				(type default)
			)
			(layer "B.Fab")
		)
		(fp_line
			(start -0.3048 0.9906)
			(end -0.3048 -0.1016)
			(stroke
				(width 0.1)
				(type default)
			)
			(layer "B.Fab")
		)
		(pad "1" smd rect
			(at 0 0 270)
			(size 0.508 0.508)
			(layers "B.Cu" "B.Mask" "B.Paste")
			(net "A_TSENSE_PVCCIN_CPU0")
		)
		(pad "2" smd rect
			(at 0 0.889 270)
			(size 0.508 0.508)
			(layers "B.Cu" "B.Mask" "B.Paste")
			(net "GND")
		)
		(zone
			(layer "B.Cu")
			(hatch none 0.5)
			(connect_pads
				(clearance 0)
			)
			(min_thickness 0.25)
			(keepout
				(tracks allowed)
				(vias not_allowed)
				(pads allowed)
				(copperpour not_allowed)
				(footprints allowed)
			)
			(placement
				(enabled no)
				(sheetname "")
			)
			(fill
				(thermal_gap 0.5)
				(thermal_bridge_width 0.5)
				(island_removal_mode 0)
			)
			(polygon
				(pts
					(xy 195.4276 -80.4926) (xy 195.4276 -79.9846) (xy 195.8086 -79.9846) (xy 195.8086 -80.4926)
				)
			)
		)
		(zone
			(layer "B.Cu")
			(hatch none 0.5)
			(connect_pads
				(clearance 0)
			)
			(min_thickness 0.25)
			(keepout
				(tracks not_allowed)
				(vias allowed)
				(pads allowed)
				(copperpour not_allowed)
				(footprints allowed)
			)
			(placement
				(enabled no)
				(sheetname "")
			)
			(fill
				(thermal_gap 0.5)
				(thermal_bridge_width 0.5)
				(island_removal_mode 0)
			)
			(polygon
				(pts
					(xy 195.8086 -80.4926) (xy 195.8086 -79.9846) (xy 195.4276 -79.9846) (xy 195.4276 -80.4926)
				)
			)
		)
	)
	(footprint ""
		(layer "B.Cu")
		(at 262.587486 -79.60614 180)
		(property "Reference" "C5P17"
			(at 0 0 0)
			(layer "B.SilkS")
			(hide yes)
			(effects
				(font
					(size 1.27 1.27)
				)
				(justify mirror)
			)
		)
		(property "Value" ""
			(at 0 0 0)
			(layer "B.Fab")
			(effects
				(font
					(size 1.27 1.27)
				)
				(justify mirror)
			)
		)
		(duplicate_pad_numbers_are_jumpers no)
		(fp_poly
			(pts
				(xy 0.7239 -0.2159) (xy -0.7239 -0.2159) (xy -0.7239 1.9939) (xy 0.7239 1.9939)
			)
			(stroke
				(width 0)
				(type default)
			)
			(fill no)
			(layer "B.CrtYd")
		)
		(fp_line
			(start 0.7239 1.9939)
			(end -0.7239 1.9939)
			(stroke
				(width 0.1)
				(type default)
			)
			(layer "B.Fab")
		)
		(fp_line
			(start 0.7239 -0.2159)
			(end 0.7239 1.9939)
			(stroke
				(width 0.1)
				(type default)
			)
			(layer "B.Fab")
		)
		(fp_line
			(start -0.7239 1.9939)
			(end -0.7239 -0.2159)
			(stroke
				(width 0.1)
				(type default)
			)
			(layer "B.Fab")
		)
		(fp_line
			(start -0.7239 -0.2159)
			(end 0.7239 -0.2159)
			(stroke
				(width 0.1)
				(type default)
			)
			(layer "B.Fab")
		)
		(pad "1" smd rect
			(at 0 0)
			(size 1.27 1.016)
			(layers "B.Cu" "B.Mask" "B.Paste")
			(net "PVCCIN_CPU0")
		)
		(pad "2" smd rect
			(at 0 1.778)
			(size 1.27 1.016)
			(layers "B.Cu" "B.Mask" "B.Paste")
			(net "GND")
		)
		(zone
			(layer "B.Cu")
			(hatch none 0.5)
			(connect_pads
				(clearance 0)
			)
			(min_thickness 0.25)
			(keepout
				(tracks not_allowed)
				(vias allowed)
				(pads allowed)
				(copperpour not_allowed)
				(footprints allowed)
			)
			(placement
				(enabled no)
				(sheetname "")
			)
			(fill
				(thermal_gap 0.5)
				(thermal_bridge_width 0.5)
				(island_removal_mode 0)
			)
			(polygon
				(pts
					(xy 261.952486 -80.11414) (xy 263.222486 -80.11414) (xy 263.222486 -80.87614) (xy 261.952486 -80.87614)
				)
			)
		)
	)
	(footprint ""
		(layer "B.Cu")
		(at 493.719104 -43.056048 180)
		(property "Reference" "C25W81"
			(at 0.8382 -0.67818 180)
			(unlocked yes)
			(layer "B.SilkS")
			(effects
				(font
					(size 0.4064 0.254)
					(thickness 0.1524)
				)
				(justify left mirror)
			)
		)
		(property "Value" ""
			(at 0 0 0)
			(layer "B.Fab")
			(effects
				(font
					(size 1.27 1.27)
				)
				(justify mirror)
			)
		)
		(duplicate_pad_numbers_are_jumpers no)
		(fp_poly
			(pts
				(xy -0.3048 -0.1016) (xy -0.3048 0.9906) (xy 0.3048 0.9906) (xy 0.3048 -0.1016)
			)
			(stroke
				(width 0)
				(type default)
			)
			(fill no)
			(layer "B.CrtYd")
		)
		(fp_line
			(start 0.3048 0.9906)
			(end -0.3048 0.9906)
			(stroke
				(width 0.1)
				(type default)
			)
			(layer "B.Fab")
		)
		(fp_line
			(start 0.3048 -0.1016)
			(end 0.3048 0.9906)
			(stroke
				(width 0.1)
				(type default)
			)
			(layer "B.Fab")
		)
		(fp_line
			(start -0.3048 0.9906)
			(end -0.3048 -0.1016)
			(stroke
				(width 0.1)
				(type default)
			)
			(layer "B.Fab")
		)
		(fp_line
			(start -0.3048 -0.1016)
			(end 0.3048 -0.1016)
			(stroke
				(width 0.1)
				(type default)
			)
			(layer "B.Fab")
		)
		(pad "1" smd rect
			(at 0 0)
			(size 0.508 0.508)
			(layers "B.Cu" "B.Mask" "B.Paste")
			(net "V_IO_HSYNC_J")
		)
		(pad "2" smd rect
			(at 0 0.889)
			(size 0.508 0.508)
			(layers "B.Cu" "B.Mask" "B.Paste")
			(net "GND")
		)
		(zone
			(layer "B.Cu")
			(hatch none 0.5)
			(connect_pads
				(clearance 0)
			)
			(min_thickness 0.25)
			(keepout
				(tracks not_allowed)
				(vias allowed)
				(pads allowed)
				(copperpour not_allowed)
				(footprints allowed)
			)
			(placement
				(enabled no)
				(sheetname "")
			)
			(fill
				(thermal_gap 0.5)
				(thermal_bridge_width 0.5)
				(island_removal_mode 0)
			)
			(polygon
				(pts
					(xy 493.465104 -43.691048) (xy 493.973104 -43.691048) (xy 493.973104 -43.310048) (xy 493.465104 -43.310048)
				)
			)
		)
		(zone
			(layer "B.Cu")
			(hatch none 0.5)
			(connect_pads
				(clearance 0)
			)
			(min_thickness 0.25)
			(keepout
				(tracks allowed)
				(vias not_allowed)
				(pads allowed)
				(copperpour not_allowed)
				(footprints allowed)
			)
			(placement
				(enabled no)
				(sheetname "")
			)
			(fill
				(thermal_gap 0.5)
				(thermal_bridge_width 0.5)
				(island_removal_mode 0)
			)
			(polygon
				(pts
					(xy 493.465104 -43.310048) (xy 493.973104 -43.310048) (xy 493.973104 -43.691048) (xy 493.465104 -43.691048)
				)
			)
		)
	)
)
